(kicad_pcb
	(version 20221018)
	(generator pcbnew)
	(general
    (thickness 1.7403)
  )
	(paper "A4")
	(title_block
    (title "Data Center RDIMM DDR4 Tester")
    (date "2024-09-30")
    (rev "1.2.4")
		(comment 9 "footprints 383-392 of 690")
	)
	(layers
    (0 "F.Cu" signal)
    (1 "In1.Cu" power)
    (2 "In2.Cu" signal)
    (3 "In3.Cu" power)
    (4 "In4.Cu" power)
    (5 "In5.Cu" signal)
    (6 "In6.Cu" power)
    (7 "In7.Cu" signal)
    (8 "In8.Cu" power)
    (9 "In9.Cu" signal)
    (10 "In10.Cu" power)
    (31 "B.Cu" signal)
    (32 "B.Adhes" user "B.Adhesive")
    (33 "F.Adhes" user "F.Adhesive")
    (34 "B.Paste" user)
    (35 "F.Paste" user)
    (36 "B.SilkS" user "B.Silkscreen")
    (37 "F.SilkS" user "F.Silkscreen")
    (38 "B.Mask" user)
    (39 "F.Mask" user)
    (40 "Dwgs.User" user "User.Drawings")
    (41 "Cmts.User" user "User.Comments")
    (42 "Eco1.User" user "User.Eco1")
    (43 "Eco2.User" user "User.Eco2")
    (44 "Edge.Cuts" user)
    (45 "Margin" user)
    (46 "B.CrtYd" user "B.Courtyard")
    (47 "F.CrtYd" user "F.Courtyard")
    (48 "B.Fab" user)
    (49 "F.Fab" user)
  )
	(footprint "data-center-rdimm-ddr4-tester-footprints:R_0402_1005Metric" (layer "B.Cu")
    (at 158.686328 86.770008 90)
    (descr "Resistor SMD 0402")
    (tags "resistor SMD 0402")
    (property "Author" "Antmicro")
    (property "DNP" "DNP")
    (property "License" "Apache-2.0")
    (property "MPN" "CR0402-FX-1002GLF")
    (property "Manufacturer" "Bourns")
    (property "Sheetfile" "ethernet.kicad_sch")
    (property "Sheetname" "Ethernet")
    (property "Tolerance" "1%")
    (property "Val" "10k")
    (property "dnp" "")
    (property "exclude_from_bom" "")
    (property "ki_description" "10k resistor in 0402 package with 1% tolerance")
    (attr exclude_from_pos_files exclude_from_bom)
    (fp_text reference "R71" (at 1.170008 8.103672 270) (layer "B.SilkS")
        (effects (font (size 0.7 0.7) (thickness 0.15)) (justify left bottom mirror))
    )
    (fp_text value "R_10k_0402" (at 0 -1.4 270) (layer "B.Fab") hide
        (effects (font (size 0.7 0.7) (thickness 0.15)) (justify left bottom mirror))
    )
    (fp_text user "${REFERENCE}" (at -0.95 -3.168 270) (layer "B.Fab") hide
        (effects (font (size 0.7 0.7) (thickness 0.15)) (justify left bottom mirror))
    )
    (fp_text user "License: Apache-2.0" (at -0.95 -5.169 270) (layer "B.Fab") hide
        (effects (font (size 0.7 0.7) (thickness 0.15)) (justify left bottom mirror))
    )
    (fp_text user "Author: Antmicro" (at -0.95 -4.169 270) (layer "B.Fab") hide
        (effects (font (size 0.7 0.7) (thickness 0.15)) (justify left bottom mirror))
    )
    (fp_rect (start -0.93 0.47) (end 0.93 -0.47)
      (stroke (width 0.05) (type solid)) (fill none) (layer "B.CrtYd"))
    (fp_rect (start -0.5 0.25) (end 0.5 -0.25)
      (stroke (width 0.15) (type solid)) (fill none) (layer "B.Fab"))
    (pad "1" smd roundrect (at -0.485 0 90) (size 0.59 0.64) (layers "B.Cu" "B.Paste" "B.Mask") (roundrect_rratio 0.25)
      (net 27 "ETH_RXD1") (pintype "passive"))
    (pad "2" smd roundrect (at 0.485 0 90) (size 0.59 0.64) (layers "B.Cu" "B.Paste" "B.Mask") (roundrect_rratio 0.25)
      (net 143 "3V3_SYS") (pintype "passive"))
  )
	(footprint "data-center-rdimm-ddr4-tester-footprints:R_0402_1005Metric" (layer "B.Cu")
    (at 155.936328 90.460008 180)
    (descr "Resistor SMD 0402")
    (tags "resistor SMD 0402")
    (property "Author" "Antmicro")
    (property "DNP" "DNP")
    (property "License" "Apache-2.0")
    (property "MPN" "CR0402-FX-1002GLF")
    (property "Manufacturer" "Bourns")
    (property "Sheetfile" "ethernet.kicad_sch")
    (property "Sheetname" "Ethernet")
    (property "Tolerance" "1%")
    (property "Val" "10k")
    (property "dnp" "")
    (property "exclude_from_bom" "")
    (property "ki_description" "10k resistor in 0402 package with 1% tolerance")
    (attr exclude_from_pos_files exclude_from_bom)
    (fp_text reference "R74" (at -8.673672 -0.389992) (layer "B.SilkS")
        (effects (font (size 0.7 0.7) (thickness 0.15)) (justify left bottom mirror))
    )
    (fp_text value "R_10k_0402" (at 0 -1.4) (layer "B.Fab") hide
        (effects (font (size 0.7 0.7) (thickness 0.15)) (justify left bottom mirror))
    )
    (fp_text user "License: Apache-2.0" (at -0.95 -5.169) (layer "B.Fab") hide
        (effects (font (size 0.7 0.7) (thickness 0.15)) (justify left bottom mirror))
    )
    (fp_text user "${REFERENCE}" (at -0.95 -3.168) (layer "B.Fab") hide
        (effects (font (size 0.7 0.7) (thickness 0.15)) (justify left bottom mirror))
    )
    (fp_text user "Author: Antmicro" (at -0.95 -4.169) (layer "B.Fab") hide
        (effects (font (size 0.7 0.7) (thickness 0.15)) (justify left bottom mirror))
    )
    (fp_rect (start -0.93 0.47) (end 0.93 -0.47)
      (stroke (width 0.05) (type solid)) (fill none) (layer "B.CrtYd"))
    (fp_rect (start -0.5 0.25) (end 0.5 -0.25)
      (stroke (width 0.15) (type solid)) (fill none) (layer "B.Fab"))
    (pad "1" smd roundrect (at -0.485 0 180) (size 0.59 0.64) (layers "B.Cu" "B.Paste" "B.Mask") (roundrect_rratio 0.25)
      (net 38 "ETH_RX_DV") (pintype "passive"))
    (pad "2" smd roundrect (at 0.485 0 180) (size 0.59 0.64) (layers "B.Cu" "B.Paste" "B.Mask") (roundrect_rratio 0.25)
      (net 143 "3V3_SYS") (pintype "passive"))
  )
	(footprint "data-center-rdimm-ddr4-tester-footprints:R_0402_1005Metric" (layer "B.Cu")
    (at 156.186328 85.610008 90)
    (descr "Resistor SMD 0402")
    (tags "resistor SMD 0402")
    (property "Author" "Antmicro")
    (property "DNP" "DNP")
    (property "License" "Apache-2.0")
    (property "MPN" "CR0402-FX-1002GLF")
    (property "Manufacturer" "Bourns")
    (property "Sheetfile" "ethernet.kicad_sch")
    (property "Sheetname" "Ethernet")
    (property "Tolerance" "1%")
    (property "Val" "10k")
    (property "dnp" "")
    (property "exclude_from_bom" "")
    (property "ki_description" "10k resistor in 0402 package with 1% tolerance")
    (attr exclude_from_pos_files exclude_from_bom)
    (fp_text reference "R75" (at 1.170008 8.103672 270) (layer "B.SilkS")
        (effects (font (size 0.7 0.7) (thickness 0.15)) (justify left bottom mirror))
    )
    (fp_text value "R_10k_0402" (at 0 -1.4 270) (layer "B.Fab") hide
        (effects (font (size 0.7 0.7) (thickness 0.15)) (justify left bottom mirror))
    )
    (fp_text user "Author: Antmicro" (at -0.95 -4.169 270) (layer "B.Fab") hide
        (effects (font (size 0.7 0.7) (thickness 0.15)) (justify left bottom mirror))
    )
    (fp_text user "License: Apache-2.0" (at -0.95 -5.169 270) (layer "B.Fab") hide
        (effects (font (size 0.7 0.7) (thickness 0.15)) (justify left bottom mirror))
    )
    (fp_text user "${REFERENCE}" (at -0.95 -3.168 270) (layer "B.Fab") hide
        (effects (font (size 0.7 0.7) (thickness 0.15)) (justify left bottom mirror))
    )
    (fp_rect (start -0.93 0.47) (end 0.93 -0.47)
      (stroke (width 0.05) (type solid)) (fill none) (layer "B.CrtYd"))
    (fp_rect (start -0.5 0.25) (end 0.5 -0.25)
      (stroke (width 0.15) (type solid)) (fill none) (layer "B.Fab"))
    (pad "1" smd roundrect (at -0.485 0 90) (size 0.59 0.64) (layers "B.Cu" "B.Paste" "B.Mask") (roundrect_rratio 0.25)
      (net 40 "ETH_RX_CLK") (pintype "passive"))
    (pad "2" smd roundrect (at 0.485 0 90) (size 0.59 0.64) (layers "B.Cu" "B.Paste" "B.Mask") (roundrect_rratio 0.25)
      (net 143 "3V3_SYS") (pintype "passive"))
  )
	(footprint "data-center-rdimm-ddr4-tester-footprints:R_0402_1005Metric" (layer "B.Cu")
    (at 156.376328 96.390008 -90)
    (descr "Resistor SMD 0402")
    (tags "resistor SMD 0402")
    (property "Author" "Antmicro")
    (property "License" "Apache-2.0")
    (property "MPN" "CR0402-FX-1002GLF")
    (property "Manufacturer" "Bourns")
    (property "Sheetfile" "ethernet.kicad_sch")
    (property "Sheetname" "Ethernet")
    (property "Tolerance" "1%")
    (property "Val" "10k")
    (property "ki_description" "10k resistor in 0402 package with 1% tolerance")
    (attr smd)
    (fp_text reference "R76" (at -1.020008 -1.293672 90) (layer "B.SilkS")
        (effects (font (size 0.7 0.7) (thickness 0.15)) (justify left bottom mirror))
    )
    (fp_text value "R_10k_0402" (at 0 -1.4 90) (layer "B.Fab") hide
        (effects (font (size 0.7 0.7) (thickness 0.15)) (justify left bottom mirror))
    )
    (fp_text user "License: Apache-2.0" (at -0.95 -5.169 90) (layer "B.Fab") hide
        (effects (font (size 0.7 0.7) (thickness 0.15)) (justify left bottom mirror))
    )
    (fp_text user "Author: Antmicro" (at -0.95 -4.169 90) (layer "B.Fab") hide
        (effects (font (size 0.7 0.7) (thickness 0.15)) (justify left bottom mirror))
    )
    (fp_text user "${REFERENCE}" (at -0.95 -3.168 90) (layer "B.Fab") hide
        (effects (font (size 0.7 0.7) (thickness 0.15)) (justify left bottom mirror))
    )
    (fp_rect (start -0.93 0.47) (end 0.93 -0.47)
      (stroke (width 0.05) (type solid)) (fill none) (layer "B.CrtYd"))
    (fp_rect (start -0.5 0.25) (end 0.5 -0.25)
      (stroke (width 0.15) (type solid)) (fill none) (layer "B.Fab"))
    (pad "1" smd roundrect (at -0.485 0 270) (size 0.59 0.64) (layers "B.Cu" "B.Paste" "B.Mask") (roundrect_rratio 0.25)
      (net 30 "ETH_REF_CLK") (pintype "passive"))
    (pad "2" smd roundrect (at 0.485 0 270) (size 0.59 0.64) (layers "B.Cu" "B.Paste" "B.Mask") (roundrect_rratio 0.25)
      (net 143 "3V3_SYS") (pintype "passive"))
  )
	(footprint "data-center-rdimm-ddr4-tester-footprints:R_0402_1005Metric" (layer "B.Cu")
    (at 154.886328 96.320008)
    (descr "Resistor SMD 0402")
    (tags "resistor SMD 0402")
    (property "Author" "Antmicro")
    (property "License" "Apache-2.0")
    (property "MPN" "CR0402-FX-1002GLF")
    (property "Manufacturer" "Bourns")
    (property "Sheetfile" "ethernet.kicad_sch")
    (property "Sheetname" "Ethernet")
    (property "Tolerance" "1%")
    (property "Val" "10k")
    (property "ki_description" "10k resistor in 0402 package with 1% tolerance")
    (attr smd)
    (fp_text reference "R79" (at 1.073672 1.309992 180) (layer "B.SilkS")
        (effects (font (size 0.7 0.7) (thickness 0.15)) (justify left bottom mirror))
    )
    (fp_text value "R_10k_0402" (at 0 -1.4 180) (layer "B.Fab") hide
        (effects (font (size 0.7 0.7) (thickness 0.15)) (justify left bottom mirror))
    )
    (fp_text user "License: Apache-2.0" (at -0.95 -5.169 180) (layer "B.Fab") hide
        (effects (font (size 0.7 0.7) (thickness 0.15)) (justify left bottom mirror))
    )
    (fp_text user "${REFERENCE}" (at -0.95 -3.168 180) (layer "B.Fab") hide
        (effects (font (size 0.7 0.7) (thickness 0.15)) (justify left bottom mirror))
    )
    (fp_text user "Author: Antmicro" (at -0.95 -4.169 180) (layer "B.Fab") hide
        (effects (font (size 0.7 0.7) (thickness 0.15)) (justify left bottom mirror))
    )
    (fp_rect (start -0.93 0.47) (end 0.93 -0.47)
      (stroke (width 0.05) (type solid)) (fill none) (layer "B.CrtYd"))
    (fp_rect (start -0.5 0.25) (end 0.5 -0.25)
      (stroke (width 0.15) (type solid)) (fill none) (layer "B.Fab"))
    (pad "1" smd roundrect (at -0.485 0) (size 0.59 0.64) (layers "B.Cu" "B.Paste" "B.Mask") (roundrect_rratio 0.25)
      (net 28 "ETH_RSTN") (pintype "passive"))
    (pad "2" smd roundrect (at 0.485 0) (size 0.59 0.64) (layers "B.Cu" "B.Paste" "B.Mask") (roundrect_rratio 0.25)
      (net 143 "3V3_SYS") (pintype "passive"))
  )
	(footprint "data-center-rdimm-ddr4-tester-footprints:R_0402_1005Metric" (layer "B.Cu")
    (at 166.786328 98.020008)
    (descr "Resistor SMD 0402")
    (tags "resistor SMD 0402")
    (property "Author" "Antmicro")
    (property "License" "Apache-2.0")
    (property "MPN" "CR0402-FX-1002GLF")
    (property "Manufacturer" "Bourns")
    (property "Sheetfile" "ethernet.kicad_sch")
    (property "Sheetname" "Ethernet")
    (property "Tolerance" "1%")
    (property "Val" "10k")
    (property "ki_description" "10k resistor in 0402 package with 1% tolerance")
    (attr smd)
    (fp_text reference "R80" (at 3.013672 0.399992 180) (layer "B.SilkS")
        (effects (font (size 0.7 0.7) (thickness 0.15)) (justify left bottom mirror))
    )
    (fp_text value "R_10k_0402" (at 0 -1.4 180) (layer "B.Fab") hide
        (effects (font (size 0.7 0.7) (thickness 0.15)) (justify left bottom mirror))
    )
    (fp_text user "License: Apache-2.0" (at -0.95 -5.169 180) (layer "B.Fab") hide
        (effects (font (size 0.7 0.7) (thickness 0.15)) (justify left bottom mirror))
    )
    (fp_text user "Author: Antmicro" (at -0.95 -4.169 180) (layer "B.Fab") hide
        (effects (font (size 0.7 0.7) (thickness 0.15)) (justify left bottom mirror))
    )
    (fp_text user "${REFERENCE}" (at -0.95 -3.168 180) (layer "B.Fab") hide
        (effects (font (size 0.7 0.7) (thickness 0.15)) (justify left bottom mirror))
    )
    (fp_rect (start -0.93 0.47) (end 0.93 -0.47)
      (stroke (width 0.05) (type solid)) (fill none) (layer "B.CrtYd"))
    (fp_rect (start -0.5 0.25) (end 0.5 -0.25)
      (stroke (width 0.15) (type solid)) (fill none) (layer "B.Fab"))
    (pad "1" smd roundrect (at -0.485 0) (size 0.59 0.64) (layers "B.Cu" "B.Paste" "B.Mask") (roundrect_rratio 0.25)
      (net 17 "LED_SPD") (pintype "passive"))
    (pad "2" smd roundrect (at 0.485 0) (size 0.59 0.64) (layers "B.Cu" "B.Paste" "B.Mask") (roundrect_rratio 0.25)
      (net 143 "3V3_SYS") (pintype "passive"))
  )
	(footprint "data-center-rdimm-ddr4-tester-footprints:R_0402_1005Metric" (layer "B.Cu")
    (at 166.786328 96.520008)
    (descr "Resistor SMD 0402")
    (tags "resistor SMD 0402")
    (property "Author" "Antmicro")
    (property "License" "Apache-2.0")
    (property "MPN" "CR0402-FX-1002GLF")
    (property "Manufacturer" "Bourns")
    (property "Sheetfile" "ethernet.kicad_sch")
    (property "Sheetname" "Ethernet")
    (property "Tolerance" "1%")
    (property "Val" "10k")
    (property "ki_description" "10k resistor in 0402 package with 1% tolerance")
    (attr smd)
    (fp_text reference "R81" (at 3.053672 0.349992 180) (layer "B.SilkS")
        (effects (font (size 0.7 0.7) (thickness 0.15)) (justify left bottom mirror))
    )
    (fp_text value "R_10k_0402" (at 0 -1.4 180) (layer "B.Fab") hide
        (effects (font (size 0.7 0.7) (thickness 0.15)) (justify left bottom mirror))
    )
    (fp_text user "Author: Antmicro" (at -0.95 -4.169 180) (layer "B.Fab") hide
        (effects (font (size 0.7 0.7) (thickness 0.15)) (justify left bottom mirror))
    )
    (fp_text user "${REFERENCE}" (at -0.95 -3.168 180) (layer "B.Fab") hide
        (effects (font (size 0.7 0.7) (thickness 0.15)) (justify left bottom mirror))
    )
    (fp_text user "License: Apache-2.0" (at -0.95 -5.169 180) (layer "B.Fab") hide
        (effects (font (size 0.7 0.7) (thickness 0.15)) (justify left bottom mirror))
    )
    (fp_rect (start -0.93 0.47) (end 0.93 -0.47)
      (stroke (width 0.05) (type solid)) (fill none) (layer "B.CrtYd"))
    (fp_rect (start -0.5 0.25) (end 0.5 -0.25)
      (stroke (width 0.15) (type solid)) (fill none) (layer "B.Fab"))
    (pad "1" smd roundrect (at -0.485 0) (size 0.59 0.64) (layers "B.Cu" "B.Paste" "B.Mask") (roundrect_rratio 0.25)
      (net 16 "LED_LINK") (pintype "passive"))
    (pad "2" smd roundrect (at 0.485 0) (size 0.59 0.64) (layers "B.Cu" "B.Paste" "B.Mask") (roundrect_rratio 0.25)
      (net 143 "3V3_SYS") (pintype "passive"))
  )
	(footprint "data-center-rdimm-ddr4-tester-footprints:C_0402_1005Metric" (layer "B.Cu")
    (at 157.1 98.5 90)
    (descr "Capacitor SMD 0402")
    (tags "capacitor SMD 0402")
    (property "Author" "Antmicro")
    (property "Dielectric" "")
    (property "License" "Apache-2.0")
    (property "MPN" "GRM155R61A475MEAAD")
    (property "Manufacturer" "Murata")
    (property "Sheetfile" "ethernet.kicad_sch")
    (property "Sheetname" "Ethernet")
    (property "Val" "4u7")
    (property "Voltage" "")
    (property "ki_description" " ")
    (attr smd)
    (fp_text reference "C121" (at 0.79 -0.44 270) (layer "B.SilkS")
        (effects (font (size 0.7 0.7) (thickness 0.15)) (justify left bottom mirror))
    )
    (fp_text value "C_4u7_0402" (at 0 -1.4 270) (layer "B.Fab") hide
        (effects (font (size 0.7 0.7) (thickness 0.15)) (justify left bottom mirror))
    )
    (fp_text user "${REFERENCE}" (at -0.932 -3.168 270) (layer "B.Fab") hide
        (effects (font (size 0.7 0.7) (thickness 0.15)) (justify left bottom mirror))
    )
    (fp_text user "Author: Antmicro" (at -0.932 -4.17 270) (layer "B.Fab") hide
        (effects (font (size 0.7 0.7) (thickness 0.15)) (justify left bottom mirror))
    )
    (fp_text user "License: Apache-2.0" (at -0.932 -5.17 270) (layer "B.Fab") hide
        (effects (font (size 0.7 0.7) (thickness 0.15)) (justify left bottom mirror))
    )
    (fp_rect (start -0.94 0.47) (end 0.94 -0.47)
      (stroke (width 0.05) (type solid)) (fill none) (layer "B.CrtYd"))
    (fp_rect (start -0.499 0.249) (end 0.499 -0.249)
      (stroke (width 0.15) (type solid)) (fill none) (layer "B.Fab"))
    (pad "1" smd roundrect (at -0.484 0 90) (size 0.59 0.64) (layers "B.Cu" "B.Paste" "B.Mask") (roundrect_rratio 0.25)
      (net 177 "/Ethernet/AVDDL") (pintype "passive"))
    (pad "2" smd roundrect (at 0.484 0 90) (size 0.59 0.64) (layers "B.Cu" "B.Paste" "B.Mask") (roundrect_rratio 0.25)
      (net 9 "GND") (pintype "passive"))
  )
	(footprint "data-center-rdimm-ddr4-tester-footprints:C_0402_1005Metric" (layer "B.Cu")
    (at 157.486328 93.020008 -90)
    (descr "Capacitor SMD 0402")
    (tags "capacitor SMD 0402")
    (property "Author" "Antmicro")
    (property "Dielectric" "")
    (property "License" "Apache-2.0")
    (property "MPN" "C1005X5R1E474M050BB")
    (property "Manufacturer" "TDK")
    (property "Sheetfile" "ethernet.kicad_sch")
    (property "Sheetname" "Ethernet")
    (property "Val" "470n")
    (property "Voltage" "")
    (property "ki_description" " ")
    (attr smd)
    (fp_text reference "C122" (at -1.449008 -6.503672 90) (layer "B.SilkS")
        (effects (font (size 0.7 0.7) (thickness 0.15)) (justify left bottom mirror))
    )
    (fp_text value "C_470n_0402" (at 0 -1.4 90) (layer "B.Fab") hide
        (effects (font (size 0.7 0.7) (thickness 0.15)) (justify left bottom mirror))
    )
    (fp_text user "Author: Antmicro" (at -0.932 -4.17 90) (layer "B.Fab") hide
        (effects (font (size 0.7 0.7) (thickness 0.15)) (justify left bottom mirror))
    )
    (fp_text user "License: Apache-2.0" (at -0.932 -5.17 90) (layer "B.Fab") hide
        (effects (font (size 0.7 0.7) (thickness 0.15)) (justify left bottom mirror))
    )
    (fp_text user "${REFERENCE}" (at -0.932 -3.168 90) (layer "B.Fab") hide
        (effects (font (size 0.7 0.7) (thickness 0.15)) (justify left bottom mirror))
    )
    (fp_rect (start -0.94 0.47) (end 0.94 -0.47)
      (stroke (width 0.05) (type solid)) (fill none) (layer "B.CrtYd"))
    (fp_rect (start -0.499 0.249) (end 0.499 -0.249)
      (stroke (width 0.15) (type solid)) (fill none) (layer "B.Fab"))
    (pad "1" smd roundrect (at -0.484 0 270) (size 0.59 0.64) (layers "B.Cu" "B.Paste" "B.Mask") (roundrect_rratio 0.25)
      (net 306 "1V2_SYS") (pintype "passive"))
    (pad "2" smd roundrect (at 0.484 0 270) (size 0.59 0.64) (layers "B.Cu" "B.Paste" "B.Mask") (roundrect_rratio 0.25)
      (net 9 "GND") (pintype "passive"))
  )
	(footprint "data-center-rdimm-ddr4-tester-footprints:C_0402_1005Metric" (layer "B.Cu")
    (at 155.486328 93.020008 -90)
    (descr "Capacitor SMD 0402")
    (tags "capacitor SMD 0402")
    (property "Author" "Antmicro")
    (property "Dielectric" "")
    (property "License" "Apache-2.0")
    (property "MPN" "GRM155R61A475MEAAD")
    (property "Manufacturer" "Murata")
    (property "Sheetfile" "ethernet.kicad_sch")
    (property "Sheetname" "Ethernet")
    (property "Val" "4u7")
    (property "Voltage" "")
    (property "ki_description" " ")
    (attr smd)
    (fp_text reference "C123" (at -1.449008 -6.503672 90) (layer "B.SilkS")
        (effects (font (size 0.7 0.7) (thickness 0.15)) (justify left bottom mirror))
    )
    (fp_text value "C_4u7_0402" (at 0 -1.4 90) (layer "B.Fab") hide
        (effects (font (size 0.7 0.7) (thickness 0.15)) (justify left bottom mirror))
    )
    (fp_text user "License: Apache-2.0" (at -0.932 -5.17 90) (layer "B.Fab") hide
        (effects (font (size 0.7 0.7) (thickness 0.15)) (justify left bottom mirror))
    )
    (fp_text user "Author: Antmicro" (at -0.932 -4.17 90) (layer "B.Fab") hide
        (effects (font (size 0.7 0.7) (thickness 0.15)) (justify left bottom mirror))
    )
    (fp_text user "${REFERENCE}" (at -0.932 -3.168 90) (layer "B.Fab") hide
        (effects (font (size 0.7 0.7) (thickness 0.15)) (justify left bottom mirror))
    )
    (fp_rect (start -0.94 0.47) (end 0.94 -0.47)
      (stroke (width 0.05) (type solid)) (fill none) (layer "B.CrtYd"))
    (fp_rect (start -0.499 0.249) (end 0.499 -0.249)
      (stroke (width 0.15) (type solid)) (fill none) (layer "B.Fab"))
    (pad "1" smd roundrect (at -0.484 0 270) (size 0.59 0.64) (layers "B.Cu" "B.Paste" "B.Mask") (roundrect_rratio 0.25)
      (net 143 "3V3_SYS") (pintype "passive"))
    (pad "2" smd roundrect (at 0.484 0 270) (size 0.59 0.64) (layers "B.Cu" "B.Paste" "B.Mask") (roundrect_rratio 0.25)
      (net 9 "GND") (pintype "passive"))
  )
)
